(kicad_pcb
	(version 20241229)
	(generator "pcbnew")
	(generator_version "9.0")
	(general
		(thickness 1.6)
		(legacy_teardrops no)
	)
	(paper "A4")
	(title_block
		(title "LPDDR4 testbed")
		(date "2024-03-26")
		(rev "1.2.2")
		(comment 9 "footprints 9-15 of 66")
	)
	(layers
		(0 "F.Cu" signal)
		(4 "In1.Cu" power)
		(6 "In2.Cu" power)
		(8 "In3.Cu" signal)
		(10 "In4.Cu" signal)
		(2 "B.Cu" signal)
		(9 "F.Adhes" user "F.Adhesive")
		(11 "B.Adhes" user "B.Adhesive")
		(13 "F.Paste" user)
		(15 "B.Paste" user)
		(5 "F.SilkS" user "F.Silkscreen")
		(7 "B.SilkS" user "B.Silkscreen")
		(1 "F.Mask" user)
		(3 "B.Mask" user)
		(17 "Dwgs.User" user "User.Drawings")
		(19 "Cmts.User" user "User.Comments")
		(21 "Eco1.User" user "User.Eco1")
		(23 "Eco2.User" user "User.Eco2")
		(25 "Edge.Cuts" user)
		(27 "Margin" user)
		(31 "F.CrtYd" user "F.Courtyard")
		(29 "B.CrtYd" user "B.Courtyard")
		(35 "F.Fab" user)
		(33 "B.Fab" user)
	)
	(footprint "antmicro-footprints:C_0201"
		(layer "F.Cu")
		(at 142.725 91.05 90)
		(descr "Capacitor SMD 0201")
		(tags "capacitor SMD 0201")
		(property "Reference" "C14"
			(at -2.9 0.25 90)
			(layer "F.SilkS")
			(effects
				(font
					(size 0.7 0.7)
					(thickness 0.15)
				)
				(justify left bottom)
			)
		)
		(property "Value" "C_100n_0201"
			(at 0 1.4 90)
			(layer "F.Fab")
			(effects
				(font
					(size 0.7 0.7)
					(thickness 0.15)
				)
				(justify left bottom)
			)
		)
		(property "Description" " "
			(at 0 0 90)
			(layer "F.Fab")
			(hide yes)
			(effects
				(font
					(size 1.27 1.27)
					(thickness 0.15)
				)
			)
		)
		(property "Author" "Antmicro"
			(at 233.775 -51.675 0)
			(layer "F.Fab")
			(hide yes)
			(effects
				(font
					(size 1 1)
					(thickness 0.15)
				)
			)
		)
		(property "Dielectric" ""
			(at 233.775 -51.675 0)
			(layer "F.Fab")
			(hide yes)
			(effects
				(font
					(size 1 1)
					(thickness 0.15)
				)
			)
		)
		(property "License" "Apache-2.0"
			(at 233.775 -51.675 0)
			(layer "F.Fab")
			(hide yes)
			(effects
				(font
					(size 1 1)
					(thickness 0.15)
				)
			)
		)
		(property "MPN" "CC0201KRX6S5BB104"
			(at 233.775 -51.675 0)
			(layer "F.Fab")
			(hide yes)
			(effects
				(font
					(size 1 1)
					(thickness 0.15)
				)
			)
		)
		(property "Manufacturer" "YAGEO"
			(at 233.775 -51.675 0)
			(layer "F.Fab")
			(hide yes)
			(effects
				(font
					(size 1 1)
					(thickness 0.15)
				)
			)
		)
		(property "Val" "100n"
			(at 233.775 -51.675 0)
			(layer "F.Fab")
			(hide yes)
			(effects
				(font
					(size 1 1)
					(thickness 0.15)
				)
			)
		)
		(property "Voltage" ""
			(at 233.775 -51.675 0)
			(layer "F.Fab")
			(hide yes)
			(effects
				(font
					(size 1 1)
					(thickness 0.15)
				)
			)
		)
		(sheetname "LPDDR4")
		(sheetfile "lpddr4.kicad_sch")
		(attr smd)
		(fp_rect
			(start -0.72 -0.38)
			(end 0.72 0.38)
			(stroke
				(width 0.05)
				(type solid)
			)
			(fill no)
			(layer "F.CrtYd")
		)
		(fp_rect
			(start 0.3 0.15)
			(end -0.301 -0.149)
			(stroke
				(width 0.15)
				(type solid)
			)
			(fill no)
			(layer "F.Fab")
		)
		(pad "" smd roundrect
			(at -0.349 -0.002 90)
			(size 0.318 0.36)
			(layers "F.Paste")
			(roundrect_rratio 0.25)
		)
		(pad "" smd roundrect
			(at 0.341 -0.002 90)
			(size 0.318 0.36)
			(layers "F.Paste")
			(roundrect_rratio 0.25)
		)
		(pad "1" smd roundrect
			(at -0.321 -0.002 90)
			(size 0.46 0.4)
			(layers "F.Cu" "F.Mask")
			(roundrect_rratio 0.25)
			(net 36 "GND")
			(pintype "passive")
		)
		(pad "2" smd roundrect
			(at 0.32 -0.002 90)
			(size 0.46 0.4)
			(layers "F.Cu" "F.Mask")
			(roundrect_rratio 0.25)
			(net 189 "VDDQ")
			(pintype "passive")
		)
	)
	(footprint "antmicro-footprints:C_0201"
		(layer "F.Cu")
		(at 142.925 87.6 -90)
		(descr "Capacitor SMD 0201")
		(tags "capacitor SMD 0201")
		(property "Reference" "C20"
			(at -1.25 0.55 90)
			(layer "F.SilkS")
			(effects
				(font
					(size 0.7 0.7)
					(thickness 0.15)
				)
				(justify right bottom)
			)
		)
		(property "Value" "C_100n_0201"
			(at 0 1.4 90)
			(layer "F.Fab")
			(effects
				(font
					(size 0.7 0.7)
					(thickness 0.15)
				)
				(justify right bottom)
			)
		)
		(property "Description" " "
			(at 0 0 270)
			(layer "F.Fab")
			(hide yes)
			(effects
				(font
					(size 1.27 1.27)
					(thickness 0.15)
				)
			)
		)
		(property "Author" "Antmicro"
			(at 55.325 230.525 0)
			(layer "F.Fab")
			(hide yes)
			(effects
				(font
					(size 1 1)
					(thickness 0.15)
				)
			)
		)
		(property "Dielectric" ""
			(at 55.325 230.525 0)
			(layer "F.Fab")
			(hide yes)
			(effects
				(font
					(size 1 1)
					(thickness 0.15)
				)
			)
		)
		(property "License" "Apache-2.0"
			(at 55.325 230.525 0)
			(layer "F.Fab")
			(hide yes)
			(effects
				(font
					(size 1 1)
					(thickness 0.15)
				)
			)
		)
		(property "MPN" "CC0201KRX6S5BB104"
			(at 55.325 230.525 0)
			(layer "F.Fab")
			(hide yes)
			(effects
				(font
					(size 1 1)
					(thickness 0.15)
				)
			)
		)
		(property "Manufacturer" "YAGEO"
			(at 55.325 230.525 0)
			(layer "F.Fab")
			(hide yes)
			(effects
				(font
					(size 1 1)
					(thickness 0.15)
				)
			)
		)
		(property "Val" "100n"
			(at 55.325 230.525 0)
			(layer "F.Fab")
			(hide yes)
			(effects
				(font
					(size 1 1)
					(thickness 0.15)
				)
			)
		)
		(property "Voltage" ""
			(at 55.325 230.525 0)
			(layer "F.Fab")
			(hide yes)
			(effects
				(font
					(size 1 1)
					(thickness 0.15)
				)
			)
		)
		(sheetname "LPDDR4")
		(sheetfile "lpddr4.kicad_sch")
		(attr smd)
		(fp_rect
			(start -0.72 -0.38)
			(end 0.72 0.38)
			(stroke
				(width 0.05)
				(type solid)
			)
			(fill no)
			(layer "F.CrtYd")
		)
		(fp_rect
			(start 0.3 0.15)
			(end -0.301 -0.149)
			(stroke
				(width 0.15)
				(type solid)
			)
			(fill no)
			(layer "F.Fab")
		)
		(pad "" smd roundrect
			(at -0.349 -0.002 270)
			(size 0.318 0.36)
			(layers "F.Paste")
			(roundrect_rratio 0.25)
		)
		(pad "" smd roundrect
			(at 0.341 -0.002 270)
			(size 0.318 0.36)
			(layers "F.Paste")
			(roundrect_rratio 0.25)
		)
		(pad "1" smd roundrect
			(at -0.321 -0.002 270)
			(size 0.46 0.4)
			(layers "F.Cu" "F.Mask")
			(roundrect_rratio 0.25)
			(net 36 "GND")
			(pintype "passive")
		)
		(pad "2" smd roundrect
			(at 0.32 -0.002 270)
			(size 0.46 0.4)
			(layers "F.Cu" "F.Mask")
			(roundrect_rratio 0.25)
			(net 188 "VDD2")
			(pintype "passive")
		)
	)
	(footprint "antmicro-footprints:C_0201"
		(layer "F.Cu")
		(at 155.855 91.7 90)
		(descr "Capacitor SMD 0201")
		(tags "capacitor SMD 0201")
		(property "Reference" "C21"
			(at -1.05 1.22 90)
			(layer "F.SilkS")
			(effects
				(font
					(size 0.7 0.7)
					(thickness 0.15)
				)
				(justify left bottom)
			)
		)
		(property "Value" "C_100n_0201"
			(at 0 1.4 90)
			(layer "F.Fab")
			(effects
				(font
					(size 0.7 0.7)
					(thickness 0.15)
				)
				(justify left bottom)
			)
		)
		(property "Description" " "
			(at 0 0 90)
			(layer "F.Fab")
			(hide yes)
			(effects
				(font
					(size 1.27 1.27)
					(thickness 0.15)
				)
			)
		)
		(property "Author" "Antmicro"
			(at 247.555 -64.155 0)
			(layer "F.Fab")
			(hide yes)
			(effects
				(font
					(size 1 1)
					(thickness 0.15)
				)
			)
		)
		(property "Dielectric" ""
			(at 247.555 -64.155 0)
			(layer "F.Fab")
			(hide yes)
			(effects
				(font
					(size 1 1)
					(thickness 0.15)
				)
			)
		)
		(property "License" "Apache-2.0"
			(at 247.555 -64.155 0)
			(layer "F.Fab")
			(hide yes)
			(effects
				(font
					(size 1 1)
					(thickness 0.15)
				)
			)
		)
		(property "MPN" "CC0201KRX6S5BB104"
			(at 247.555 -64.155 0)
			(layer "F.Fab")
			(hide yes)
			(effects
				(font
					(size 1 1)
					(thickness 0.15)
				)
			)
		)
		(property "Manufacturer" "YAGEO"
			(at 247.555 -64.155 0)
			(layer "F.Fab")
			(hide yes)
			(effects
				(font
					(size 1 1)
					(thickness 0.15)
				)
			)
		)
		(property "Val" "100n"
			(at 247.555 -64.155 0)
			(layer "F.Fab")
			(hide yes)
			(effects
				(font
					(size 1 1)
					(thickness 0.15)
				)
			)
		)
		(property "Voltage" ""
			(at 247.555 -64.155 0)
			(layer "F.Fab")
			(hide yes)
			(effects
				(font
					(size 1 1)
					(thickness 0.15)
				)
			)
		)
		(sheetname "LPDDR4")
		(sheetfile "lpddr4.kicad_sch")
		(attr smd)
		(fp_rect
			(start -0.72 -0.38)
			(end 0.72 0.38)
			(stroke
				(width 0.05)
				(type solid)
			)
			(fill no)
			(layer "F.CrtYd")
		)
		(fp_rect
			(start 0.3 0.15)
			(end -0.301 -0.149)
			(stroke
				(width 0.15)
				(type solid)
			)
			(fill no)
			(layer "F.Fab")
		)
		(pad "" smd roundrect
			(at -0.349 -0.002 90)
			(size 0.318 0.36)
			(layers "F.Paste")
			(roundrect_rratio 0.25)
		)
		(pad "" smd roundrect
			(at 0.341 -0.002 90)
			(size 0.318 0.36)
			(layers "F.Paste")
			(roundrect_rratio 0.25)
		)
		(pad "1" smd roundrect
			(at -0.321 -0.002 90)
			(size 0.46 0.4)
			(layers "F.Cu" "F.Mask")
			(roundrect_rratio 0.25)
			(net 36 "GND")
			(pintype "passive")
		)
		(pad "2" smd roundrect
			(at 0.32 -0.002 90)
			(size 0.46 0.4)
			(layers "F.Cu" "F.Mask")
			(roundrect_rratio 0.25)
			(net 189 "VDDQ")
			(pintype "passive")
		)
	)
	(footprint "antmicro-footprints:C_0201"
		(layer "F.Cu")
		(at 155.855 82.7 -90)
		(descr "Capacitor SMD 0201")
		(tags "capacitor SMD 0201")
		(property "Reference" "C25"
			(at -0.75 -1.22 90)
			(layer "F.SilkS")
			(effects
				(font
					(size 0.7 0.7)
					(thickness 0.15)
				)
				(justify right bottom)
			)
		)
		(property "Value" "C_100n_0201"
			(at 0 1.4 90)
			(layer "F.Fab")
			(effects
				(font
					(size 0.7 0.7)
					(thickness 0.15)
				)
				(justify right bottom)
			)
		)
		(property "Description" " "
			(at 0 0 270)
			(layer "F.Fab")
			(hide yes)
			(effects
				(font
					(size 1.27 1.27)
					(thickness 0.15)
				)
			)
		)
		(property "Author" "Antmicro"
			(at 73.155 238.555 0)
			(layer "F.Fab")
			(hide yes)
			(effects
				(font
					(size 1 1)
					(thickness 0.15)
				)
			)
		)
		(property "Dielectric" ""
			(at 73.155 238.555 0)
			(layer "F.Fab")
			(hide yes)
			(effects
				(font
					(size 1 1)
					(thickness 0.15)
				)
			)
		)
		(property "License" "Apache-2.0"
			(at 73.155 238.555 0)
			(layer "F.Fab")
			(hide yes)
			(effects
				(font
					(size 1 1)
					(thickness 0.15)
				)
			)
		)
		(property "MPN" "CC0201KRX6S5BB104"
			(at 73.155 238.555 0)
			(layer "F.Fab")
			(hide yes)
			(effects
				(font
					(size 1 1)
					(thickness 0.15)
				)
			)
		)
		(property "Manufacturer" "YAGEO"
			(at 73.155 238.555 0)
			(layer "F.Fab")
			(hide yes)
			(effects
				(font
					(size 1 1)
					(thickness 0.15)
				)
			)
		)
		(property "Val" "100n"
			(at 73.155 238.555 0)
			(layer "F.Fab")
			(hide yes)
			(effects
				(font
					(size 1 1)
					(thickness 0.15)
				)
			)
		)
		(property "Voltage" ""
			(at 73.155 238.555 0)
			(layer "F.Fab")
			(hide yes)
			(effects
				(font
					(size 1 1)
					(thickness 0.15)
				)
			)
		)
		(sheetname "LPDDR4")
		(sheetfile "lpddr4.kicad_sch")
		(attr smd)
		(fp_rect
			(start -0.72 -0.38)
			(end 0.72 0.38)
			(stroke
				(width 0.05)
				(type solid)
			)
			(fill no)
			(layer "F.CrtYd")
		)
		(fp_rect
			(start 0.3 0.15)
			(end -0.301 -0.149)
			(stroke
				(width 0.15)
				(type solid)
			)
			(fill no)
			(layer "F.Fab")
		)
		(pad "" smd roundrect
			(at -0.349 -0.002 270)
			(size 0.318 0.36)
			(layers "F.Paste")
			(roundrect_rratio 0.25)
		)
		(pad "" smd roundrect
			(at 0.341 -0.002 270)
			(size 0.318 0.36)
			(layers "F.Paste")
			(roundrect_rratio 0.25)
		)
		(pad "1" smd roundrect
			(at -0.321 -0.002 270)
			(size 0.46 0.4)
			(layers "F.Cu" "F.Mask")
			(roundrect_rratio 0.25)
			(net 36 "GND")
			(pintype "passive")
		)
		(pad "2" smd roundrect
			(at 0.32 -0.002 270)
			(size 0.46 0.4)
			(layers "F.Cu" "F.Mask")
			(roundrect_rratio 0.25)
			(net 187 "VDD1")
			(pintype "passive")
		)
	)
	(footprint "antmicro-footprints:C_0201"
		(layer "F.Cu")
		(at 152.167 94.891 180)
		(descr "Capacitor SMD 0201")
		(tags "capacitor SMD 0201")
		(property "Reference" "C26"
			(at -1.008 -1.259 0)
			(layer "F.SilkS")
			(effects
				(font
					(size 0.7 0.7)
					(thickness 0.15)
				)
				(justify right bottom)
			)
		)
		(property "Value" "C_100n_0201"
			(at 0 1.4 0)
			(layer "F.Fab")
			(effects
				(font
					(size 0.7 0.7)
					(thickness 0.15)
				)
				(justify right bottom)
			)
		)
		(property "Description" " "
			(at 0 0 180)
			(layer "F.Fab")
			(hide yes)
			(effects
				(font
					(size 1.27 1.27)
					(thickness 0.15)
				)
			)
		)
		(property "Author" "Antmicro"
			(at 304.334 189.782 0)
			(layer "F.Fab")
			(hide yes)
			(effects
				(font
					(size 1 1)
					(thickness 0.15)
				)
			)
		)
		(property "Dielectric" ""
			(at 304.334 189.782 0)
			(layer "F.Fab")
			(hide yes)
			(effects
				(font
					(size 1 1)
					(thickness 0.15)
				)
			)
		)
		(property "License" "Apache-2.0"
			(at 304.334 189.782 0)
			(layer "F.Fab")
			(hide yes)
			(effects
				(font
					(size 1 1)
					(thickness 0.15)
				)
			)
		)
		(property "MPN" "CC0201KRX6S5BB104"
			(at 304.334 189.782 0)
			(layer "F.Fab")
			(hide yes)
			(effects
				(font
					(size 1 1)
					(thickness 0.15)
				)
			)
		)
		(property "Manufacturer" "YAGEO"
			(at 304.334 189.782 0)
			(layer "F.Fab")
			(hide yes)
			(effects
				(font
					(size 1 1)
					(thickness 0.15)
				)
			)
		)
		(property "Val" "100n"
			(at 304.334 189.782 0)
			(layer "F.Fab")
			(hide yes)
			(effects
				(font
					(size 1 1)
					(thickness 0.15)
				)
			)
		)
		(property "Voltage" ""
			(at 304.334 189.782 0)
			(layer "F.Fab")
			(hide yes)
			(effects
				(font
					(size 1 1)
					(thickness 0.15)
				)
			)
		)
		(sheetname "LPDDR4")
		(sheetfile "lpddr4.kicad_sch")
		(attr smd)
		(fp_rect
			(start -0.72 -0.38)
			(end 0.72 0.38)
			(stroke
				(width 0.05)
				(type solid)
			)
			(fill no)
			(layer "F.CrtYd")
		)
		(fp_rect
			(start 0.3 0.15)
			(end -0.301 -0.149)
			(stroke
				(width 0.15)
				(type solid)
			)
			(fill no)
			(layer "F.Fab")
		)
		(pad "" smd roundrect
			(at -0.349 -0.002 180)
			(size 0.318 0.36)
			(layers "F.Paste")
			(roundrect_rratio 0.25)
		)
		(pad "" smd roundrect
			(at 0.341 -0.002 180)
			(size 0.318 0.36)
			(layers "F.Paste")
			(roundrect_rratio 0.25)
		)
		(pad "1" smd roundrect
			(at -0.321 -0.002 180)
			(size 0.46 0.4)
			(layers "F.Cu" "F.Mask")
			(roundrect_rratio 0.25)
			(net 36 "GND")
			(pintype "passive")
		)
		(pad "2" smd roundrect
			(at 0.32 -0.002 180)
			(size 0.46 0.4)
			(layers "F.Cu" "F.Mask")
			(roundrect_rratio 0.25)
			(net 188 "VDD2")
			(pintype "passive")
		)
	)
	(footprint "antmicro-footprints:C_0201"
		(layer "F.Cu")
		(at 155.855 89.75 -90)
		(descr "Capacitor SMD 0201")
		(tags "capacitor SMD 0201")
		(property "Reference" "C27"
			(at -1.1 -1.22 90)
			(layer "F.SilkS")
			(effects
				(font
					(size 0.7 0.7)
					(thickness 0.15)
				)
				(justify right bottom)
			)
		)
		(property "Value" "C_100n_0201"
			(at 0 1.4 90)
			(layer "F.Fab")
			(effects
				(font
					(size 0.7 0.7)
					(thickness 0.15)
				)
				(justify right bottom)
			)
		)
		(property "Description" " "
			(at 0 0 270)
			(layer "F.Fab")
			(hide yes)
			(effects
				(font
					(size 1.27 1.27)
					(thickness 0.15)
				)
			)
		)
		(property "Author" "Antmicro"
			(at 66.105 245.605 0)
			(layer "F.Fab")
			(hide yes)
			(effects
				(font
					(size 1 1)
					(thickness 0.15)
				)
			)
		)
		(property "Dielectric" ""
			(at 66.105 245.605 0)
			(layer "F.Fab")
			(hide yes)
			(effects
				(font
					(size 1 1)
					(thickness 0.15)
				)
			)
		)
		(property "License" "Apache-2.0"
			(at 66.105 245.605 0)
			(layer "F.Fab")
			(hide yes)
			(effects
				(font
					(size 1 1)
					(thickness 0.15)
				)
			)
		)
		(property "MPN" "CC0201KRX6S5BB104"
			(at 66.105 245.605 0)
			(layer "F.Fab")
			(hide yes)
			(effects
				(font
					(size 1 1)
					(thickness 0.15)
				)
			)
		)
		(property "Manufacturer" "YAGEO"
			(at 66.105 245.605 0)
			(layer "F.Fab")
			(hide yes)
			(effects
				(font
					(size 1 1)
					(thickness 0.15)
				)
			)
		)
		(property "Val" "100n"
			(at 66.105 245.605 0)
			(layer "F.Fab")
			(hide yes)
			(effects
				(font
					(size 1 1)
					(thickness 0.15)
				)
			)
		)
		(property "Voltage" ""
			(at 66.105 245.605 0)
			(layer "F.Fab")
			(hide yes)
			(effects
				(font
					(size 1 1)
					(thickness 0.15)
				)
			)
		)
		(sheetname "LPDDR4")
		(sheetfile "lpddr4.kicad_sch")
		(attr smd)
		(fp_rect
			(start -0.72 -0.38)
			(end 0.72 0.38)
			(stroke
				(width 0.05)
				(type solid)
			)
			(fill no)
			(layer "F.CrtYd")
		)
		(fp_rect
			(start 0.3 0.15)
			(end -0.301 -0.149)
			(stroke
				(width 0.15)
				(type solid)
			)
			(fill no)
			(layer "F.Fab")
		)
		(pad "" smd roundrect
			(at -0.349 -0.002 270)
			(size 0.318 0.36)
			(layers "F.Paste")
			(roundrect_rratio 0.25)
		)
		(pad "" smd roundrect
			(at 0.341 -0.002 270)
			(size 0.318 0.36)
			(layers "F.Paste")
			(roundrect_rratio 0.25)
		)
		(pad "1" smd roundrect
			(at -0.321 -0.002 270)
			(size 0.46 0.4)
			(layers "F.Cu" "F.Mask")
			(roundrect_rratio 0.25)
			(net 36 "GND")
			(pintype "passive")
		)
		(pad "2" smd roundrect
			(at 0.32 -0.002 270)
			(size 0.46 0.4)
			(layers "F.Cu" "F.Mask")
			(roundrect_rratio 0.25)
			(net 187 "VDD1")
			(pintype "passive")
		)
	)
	(footprint "antmicro-footprints:C_0201"
		(layer "F.Cu")
		(at 142.925 89.1 -90)
		(descr "Capacitor SMD 0201")
		(tags "capacitor SMD 0201")
		(property "Reference" "C31"
			(at -0.55 0.45 90)
			(layer "F.SilkS")
			(effects
				(font
					(size 0.7 0.7)
					(thickness 0.15)
				)
				(justify right bottom)
			)
		)
		(property "Value" "C_100n_0201"
			(at 0 1.4 90)
			(layer "F.Fab")
			(effects
				(font
					(size 0.7 0.7)
					(thickness 0.15)
				)
				(justify right bottom)
			)
		)
		(property "Description" " "
			(at 0 0 270)
			(layer "F.Fab")
			(hide yes)
			(effects
				(font
					(size 1.27 1.27)
					(thickness 0.15)
				)
			)
		)
		(property "Author" "Antmicro"
			(at 53.825 232.025 0)
			(layer "F.Fab")
			(hide yes)
			(effects
				(font
					(size 1 1)
					(thickness 0.15)
				)
			)
		)
		(property "Dielectric" ""
			(at 53.825 232.025 0)
			(layer "F.Fab")
			(hide yes)
			(effects
				(font
					(size 1 1)
					(thickness 0.15)
				)
			)
		)
		(property "License" "Apache-2.0"
			(at 53.825 232.025 0)
			(layer "F.Fab")
			(hide yes)
			(effects
				(font
					(size 1 1)
					(thickness 0.15)
				)
			)
		)
		(property "MPN" "CC0201KRX6S5BB104"
			(at 53.825 232.025 0)
			(layer "F.Fab")
			(hide yes)
			(effects
				(font
					(size 1 1)
					(thickness 0.15)
				)
			)
		)
		(property "Manufacturer" "YAGEO"
			(at 53.825 232.025 0)
			(layer "F.Fab")
			(hide yes)
			(effects
				(font
					(size 1 1)
					(thickness 0.15)
				)
			)
		)
		(property "Val" "100n"
			(at 53.825 232.025 0)
			(layer "F.Fab")
			(hide yes)
			(effects
				(font
					(size 1 1)
					(thickness 0.15)
				)
			)
		)
		(property "Voltage" ""
			(at 53.825 232.025 0)
			(layer "F.Fab")
			(hide yes)
			(effects
				(font
					(size 1 1)
					(thickness 0.15)
				)
			)
		)
		(sheetname "LPDDR4")
		(sheetfile "lpddr4.kicad_sch")
		(attr smd)
		(fp_rect
			(start -0.72 -0.38)
			(end 0.72 0.38)
			(stroke
				(width 0.05)
				(type solid)
			)
			(fill no)
			(layer "F.CrtYd")
		)
		(fp_rect
			(start 0.3 0.15)
			(end -0.301 -0.149)
			(stroke
				(width 0.15)
				(type solid)
			)
			(fill no)
			(layer "F.Fab")
		)
		(pad "" smd roundrect
			(at -0.349 -0.002 270)
			(size 0.318 0.36)
			(layers "F.Paste")
			(roundrect_rratio 0.25)
		)
		(pad "" smd roundrect
			(at 0.341 -0.002 270)
			(size 0.318 0.36)
			(layers "F.Paste")
			(roundrect_rratio 0.25)
		)
		(pad "1" smd roundrect
			(at -0.321 -0.002 270)
			(size 0.46 0.4)
			(layers "F.Cu" "F.Mask")
			(roundrect_rratio 0.25)
			(net 36 "GND")
			(pintype "passive")
		)
		(pad "2" smd roundrect
			(at 0.32 -0.002 270)
			(size 0.46 0.4)
			(layers "F.Cu" "F.Mask")
			(roundrect_rratio 0.25)
			(net 187 "VDD1")
			(pintype "passive")
		)
	)
)
